#ISCELL
  pure_quanta quanta_title_block_c *
  *
#ISCELL
  standard offpage *
  page254_i1
#ISCELL
  pure_quanta_power universal_power *
  page254_i10
#ISCELL
  pure_quanta_power universal_power *
  page254_i11
#CELL
  pure_quanta q_led *
  page254_i14
#CELL
  pure_quanta q_res *
  page254_i15
#ISCELL
  pure_quanta_power universal_power *
  page254_i16
#CELL
  pure_quanta q_led *
  page254_i17
#CELL
  pure_quanta mosfet_nch_dual *
  page254_i18
#ISCELL
  standard offpage *
  page254_i19
#ISCELL
  pure_quanta_power universal_gnd *
  page254_i2
#ISCELL
  pure_quanta_power universal_gnd *
  page254_i20
#CELL
  pure_quanta q_res *
  page254_i21
#ISCELL
  pure_quanta_power universal_power *
  page254_i22
#CELL
  pure_quanta q_led *
  page254_i23
#CELL
  pure_quanta mosfet_nch_dual *
  page254_i24
#CELL
  pure_quanta q_led *
  page254_i3
#ISCELL
  pure_quanta_power universal_power *
  page254_i31
#CELL
  pure_quanta q_res *
  page254_i32
#CELL
  pure_quanta q_led *
  page254_i33
#ISCELL
  pure_quanta_power universal_gnd *
  page254_i34
#CELL
  pure_quanta mosfet_nch_dual *
  page254_i35
#ISCELL
  standard offpage *
  page254_i36
#ISCELL
  standard offpage *
  page254_i37
#CELL
  pure_quanta mosfet_nch_dual *
  page254_i38
#ISCELL
  pure_quanta_power universal_gnd *
  page254_i39
#ISCELL
  pure_quanta_power universal_gnd *
  page254_i4
#CELL
  pure_quanta q_led *
  page254_i40
#CELL
  pure_quanta q_res *
  page254_i41
#ISCELL
  pure_quanta_power universal_power *
  page254_i42
#CELL
  pure_quanta q_led *
  page254_i43
#ISCELL
  pure_quanta_power universal_power *
  page254_i44
#CELL
  pure_quanta q_res *
  page254_i45
#ISCELL
  pure_quanta_power universal_gnd *
  page254_i46
#CELL
  pure_quanta mosfet_nch_dual *
  page254_i47
#ISCELL
  standard offpage *
  page254_i48
#ISCELL
  pure_quanta_power universal_gnd *
  page254_i5
#CELL
  pure_quanta q_res *
  page254_i8
#CELL
  pure_quanta q_res *
  page254_i9
